FILE_TYPE=LIBRARY_PARTS;
primitive 'RS53317LR';
  pin
    'VIN':
      PIN_NUMBER='(3)';
      INPUT_LOAD='(-0.01,0.01)';
    'PGOOD':
      PIN_NUMBER='(9)';
      OUTPUT_LOAD='(1.0,-1.0)';
    'PGND2':
      PIN_NUMBER='(14)';
      PINUSE='POWER';
      NO_LOAD_CHECK='Both';
      NO_IO_CHECK='Both';
      NO_ASSERT_CHECK='TRUE';
      NO_DIR_CHECK='TRUE';
      ALLOW_CONNECT='TRUE';
    'EN':
      PIN_NUMBER='(5)';
      INPUT_LOAD='(-0.01,0.01)';
    'BST':
      PIN_NUMBER='(10)';
      BIDIRECTIONAL='TRUE';
      INPUT_LOAD='(-0.01,0.01)';
      OUTPUT_LOAD='(1.0,-1.0)';
    'FB':
      PIN_NUMBER='(6)';
      INPUT_LOAD='(-0.01,0.01)';
    'AGND':
      PIN_NUMBER='(7)';
      PINUSE='POWER';
      NO_LOAD_CHECK='Both';
      NO_IO_CHECK='Both';
      NO_ASSERT_CHECK='TRUE';
      NO_DIR_CHECK='TRUE';
      ALLOW_CONNECT='TRUE';
    'VCC':
      PIN_NUMBER='(13)';
      PINUSE='POWER';
      NO_LOAD_CHECK='Both';
      NO_IO_CHECK='Both';
      NO_ASSERT_CHECK='TRUE';
      NO_DIR_CHECK='TRUE';
      ALLOW_CONNECT='TRUE';
    'PGND1':
      PIN_NUMBER='(1)';
      PINUSE='POWER';
      NO_LOAD_CHECK='Both';
      NO_IO_CHECK='Both';
      NO_ASSERT_CHECK='TRUE';
      NO_DIR_CHECK='TRUE';
      ALLOW_CONNECT='TRUE';
    'SW2':
      PIN_NUMBER='(11)';
      OUTPUT_LOAD='(1.0,-1.0)';
    'REF':
      PIN_NUMBER='(8)';
      BIDIRECTIONAL='TRUE';
      INPUT_LOAD='(-0.01,0.01)';
      OUTPUT_LOAD='(1.0,-1.0)';
    'MODE':
      PIN_NUMBER='(12)';
      INPUT_LOAD='(-0.01,0.01)';
    'CS':
      PIN_NUMBER='(4)';
      BIDIRECTIONAL='TRUE';
      INPUT_LOAD='(-0.01,0.01)';
      OUTPUT_LOAD='(1.0,-1.0)';
    'SW1':
      PIN_NUMBER='(2)';
      OUTPUT_LOAD='(1.0,-1.0)';
  end_pin;
  body
    PART_NAME='RS53317LR';
    BODY_NAME='RS53317LR';
    PHYS_DES_PREFIX='U';
    CLASS='IC';
  end_body;
end_primitive;

END.
